# S9S_MB_2U (Grand Teton) — schematic netlist excerpt (pin names and nets, part order shuffled) for the footprints in the layout excerpt that follows; sources: Cadence DE-HDL packaged netlist, KiCad conversion of 03242023_DA0F0TMBIJ0_F0T_Motherboard_J_brd_V01_OCP.brd

R3053  Q_RES  33.2 1% CHIP  pkg 0402LF  page 228 : A = SMB_HOST_3V3AUX_SDA_R5 ; B = SMB_HOST_ME_SDA
R3222  Q_RES  2K 1% CHIP  pkg 0402LF  page 236 : A = SMB_S3M_CPU0_PIROM_3V3AUX_SCL ; B = P3V3_AUX

(kicad_pcb
	(version 20260206)
	(generator "pcbnew")
	(generator_version "10.0")
	(general
		(thickness 1.6)
		(legacy_teardrops no)
	)
	(paper "A4")
	(title_block
		(title "03242023_DA0F0TMBIJ0_F0T_Motherboard_J_brd_V01_OCP.brd")
		(comment 1 "Grand Teton / footprints 1628-1629 of 6105")
	)
	(layers
		(0 "F.Cu" signal "TOP")
		(4 "In1.Cu" signal "GND")
		(6 "In2.Cu" signal "IN1")
		(8 "In3.Cu" signal "GND1")
		(10 "In4.Cu" signal "IN2")
		(12 "In5.Cu" signal "GND2")
		(14 "In6.Cu" signal "IN3")
		(16 "In7.Cu" signal "GND3")
		(18 "In8.Cu" signal "VCC")
		(20 "In9.Cu" signal "VCC1")
		(22 "In10.Cu" signal "GND4")
		(24 "In11.Cu" signal "IN4")
		(26 "In12.Cu" signal "GND5")
		(28 "In13.Cu" signal "IN5")
		(30 "In14.Cu" signal "GND6")
		(32 "In15.Cu" signal "IN6")
		(34 "In16.Cu" signal "GND7")
		(2 "B.Cu" signal "BOTTOM")
		(9 "F.Adhes" user "F.Adhesive")
		(11 "B.Adhes" user "B.Adhesive")
		(13 "F.Paste" user "Package Geometry/Pastemask Top")
		(15 "B.Paste" user "Package Geometry/Pastemask Bottom")
		(5 "F.SilkS" user "Ref Des/Silkscreen Top")
		(7 "B.SilkS" user "Ref Des/Silkscreen Bottom")
		(1 "F.Mask" user "Board Geometry/Soldermask Top")
		(3 "B.Mask" user "Board Geometry/Soldermask Bottom")
		(17 "Dwgs.User" user "User.Drawings")
		(19 "Cmts.User" user "User.Comments")
		(21 "Eco1.User" user "User.Eco1")
		(23 "Eco2.User" user "User.Eco2")
		(25 "Edge.Cuts" user "Board Geometry/Outline")
		(27 "Margin" user)
		(31 "F.CrtYd" user "Package Geometry/Place Bound Top")
		(29 "B.CrtYd" user "Package Geometry/Place Bound Bottom")
		(35 "F.Fab" user "Ref Des/Assembly Top")
		(33 "B.Fab" user "Ref Des/Assembly Bottom")
	)
	(footprint ""
		(layer "F.Cu")
		(at 9.652 -48.986948)
		(property "Reference" "R3053"
			(at 0 0 0)
			(layer "F.SilkS")
			(hide yes)
			(effects
				(font
					(size 1.27 1.27)
				)
			)
		)
		(property "Value" ""
			(at 0 0 0)
			(layer "F.Fab")
			(effects
				(font
					(size 1.27 1.27)
				)
			)
		)
		(duplicate_pad_numbers_are_jumpers no)
		(fp_line
			(start -0.7874 -0.4064)
			(end 0.7874 -0.4064)
			(stroke
				(width 0.1524)
				(type default)
			)
			(layer "F.SilkS")
		)
		(fp_line
			(start -0.7874 0.4064)
			(end -0.7874 -0.4064)
			(stroke
				(width 0.1524)
				(type default)
			)
			(layer "F.SilkS")
		)
		(fp_line
			(start 0.7874 -0.4064)
			(end 0.7874 0.4064)
			(stroke
				(width 0.1524)
				(type default)
			)
			(layer "F.SilkS")
		)
		(fp_line
			(start 0.7874 0.4064)
			(end -0.7874 0.4064)
			(stroke
				(width 0.1524)
				(type default)
			)
			(layer "F.SilkS")
		)
		(fp_line
			(start -0.67945 -0.305054)
			(end -0.12065 -0.305054)
			(stroke
				(width 0.1)
				(type default)
			)
			(layer "F.Fab")
		)
		(fp_line
			(start -0.67945 0.3048)
			(end -0.67945 -0.305054)
			(stroke
				(width 0.1)
				(type default)
			)
			(layer "F.Fab")
		)
		(fp_line
			(start -0.12065 -0.305054)
			(end -0.12065 -0.2794)
			(stroke
				(width 0.1)
				(type default)
			)
			(layer "F.Fab")
		)
		(fp_line
			(start -0.12065 -0.2794)
			(end 0.12065 -0.2794)
			(stroke
				(width 0.1)
				(type default)
			)
			(layer "F.Fab")
		)
		(fp_line
			(start -0.12065 0.2794)
			(end -0.12065 0.3048)
			(stroke
				(width 0.1)
				(type default)
			)
			(layer "F.Fab")
		)
		(fp_line
			(start -0.12065 0.3048)
			(end -0.67945 0.3048)
			(stroke
				(width 0.1)
				(type default)
			)
			(layer "F.Fab")
		)
		(fp_line
			(start 0.120396 0.2794)
			(end -0.12065 0.2794)
			(stroke
				(width 0.1)
				(type default)
			)
			(layer "F.Fab")
		)
		(fp_line
			(start 0.120396 0.3048)
			(end 0.120396 0.2794)
			(stroke
				(width 0.1)
				(type default)
			)
			(layer "F.Fab")
		)
		(fp_line
			(start 0.12065 -0.3048)
			(end 0.67945 -0.3048)
			(stroke
				(width 0.1)
				(type default)
			)
			(layer "F.Fab")
		)
		(fp_line
			(start 0.12065 -0.2794)
			(end 0.12065 -0.3048)
			(stroke
				(width 0.1)
				(type default)
			)
			(layer "F.Fab")
		)
		(fp_line
			(start 0.67945 -0.3048)
			(end 0.67945 0.3048)
			(stroke
				(width 0.1)
				(type default)
			)
			(layer "F.Fab")
		)
		(fp_line
			(start 0.67945 0.3048)
			(end 0.120396 0.3048)
			(stroke
				(width 0.1)
				(type default)
			)
			(layer "F.Fab")
		)
		(pad "1" smd circle
			(at -0.40005 0)
			(size 0 0)
			(layers "F.Cu" "F.Mask" "F.Paste")
			(net "SMB_HOST_3V3AUX_SDA_R5")
		)
		(pad "2" smd circle
			(at 0.40005 0)
			(size 0 0)
			(layers "F.Cu" "F.Mask" "F.Paste")
			(net "SMB_HOST_ME_SDA")
		)
	)
	(footprint ""
		(layer "F.Cu")
		(at 156.37129 -81.90357 -90)
		(property "Reference" "R3222"
			(at 0 0 270)
			(layer "F.SilkS")
			(hide yes)
			(effects
				(font
					(size 1.27 1.27)
				)
			)
		)
		(property "Value" ""
			(at 0 0 270)
			(layer "F.Fab")
			(effects
				(font
					(size 1.27 1.27)
				)
			)
		)
		(duplicate_pad_numbers_are_jumpers no)
		(fp_line
			(start -0.7874 0.4064)
			(end -0.7874 -0.4064)
			(stroke
				(width 0.1524)
				(type default)
			)
			(layer "F.SilkS")
		)
		(fp_line
			(start 0.7874 0.4064)
			(end -0.7874 0.4064)
			(stroke
				(width 0.1524)
				(type default)
			)
			(layer "F.SilkS")
		)
		(fp_line
			(start -0.7874 -0.4064)
			(end 0.7874 -0.4064)
			(stroke
				(width 0.1524)
				(type default)
			)
			(layer "F.SilkS")
		)
		(fp_line
			(start 0.7874 -0.4064)
			(end 0.7874 0.4064)
			(stroke
				(width 0.1524)
				(type default)
			)
			(layer "F.SilkS")
		)
		(fp_line
			(start -0.67945 0.3048)
			(end -0.67945 -0.305054)
			(stroke
				(width 0.1)
				(type default)
			)
			(layer "F.Fab")
		)
		(fp_line
			(start -0.12065 0.3048)
			(end -0.67945 0.3048)
			(stroke
				(width 0.1)
				(type default)
			)
			(layer "F.Fab")
		)
		(fp_line
			(start 0.120396 0.3048)
			(end 0.120396 0.2794)
			(stroke
				(width 0.1)
				(type default)
			)
			(layer "F.Fab")
		)
		(fp_line
			(start 0.67945 0.3048)
			(end 0.120396 0.3048)
			(stroke
				(width 0.1)
				(type default)
			)
			(layer "F.Fab")
		)
		(fp_line
			(start -0.12065 0.2794)
			(end -0.12065 0.3048)
			(stroke
				(width 0.1)
				(type default)
			)
			(layer "F.Fab")
		)
		(fp_line
			(start 0.120396 0.2794)
			(end -0.12065 0.2794)
			(stroke
				(width 0.1)
				(type default)
			)
			(layer "F.Fab")
		)
		(fp_line
			(start -0.12065 -0.2794)
			(end 0.12065 -0.2794)
			(stroke
				(width 0.1)
				(type default)
			)
			(layer "F.Fab")
		)
		(fp_line
			(start 0.12065 -0.2794)
			(end 0.12065 -0.3048)
			(stroke
				(width 0.1)
				(type default)
			)
			(layer "F.Fab")
		)
		(fp_line
			(start 0.12065 -0.3048)
			(end 0.67945 -0.3048)
			(stroke
				(width 0.1)
				(type default)
			)
			(layer "F.Fab")
		)
		(fp_line
			(start 0.67945 -0.3048)
			(end 0.67945 0.3048)
			(stroke
				(width 0.1)
				(type default)
			)
			(layer "F.Fab")
		)
		(fp_line
			(start -0.67945 -0.305054)
			(end -0.12065 -0.305054)
			(stroke
				(width 0.1)
				(type default)
			)
			(layer "F.Fab")
		)
		(fp_line
			(start -0.12065 -0.305054)
			(end -0.12065 -0.2794)
			(stroke
				(width 0.1)
				(type default)
			)
			(layer "F.Fab")
		)
		(pad "1" smd circle
			(at -0.40005 0 270)
			(size 0 0)
			(layers "F.Cu" "F.Mask" "F.Paste")
			(net "SMB_S3M_CPU0_PIROM_3V3AUX_SCL")
		)
		(pad "2" smd circle
			(at 0.40005 0 270)
			(size 0 0)
			(layers "F.Cu" "F.Mask" "F.Paste")
			(net "P3V3_AUX")
		)
	)
)
